# T6G (Grand Teton) — schematic netlist excerpt (pin names and nets, part order shuffled) for the footprints in the layout excerpt that follows; sources: Cadence DE-HDL packaged netlist, KiCad conversion of 04192023_DAF0TMB3IC0_F0TG_MB_C_brd_V02_OCP.brd

R6171  Q_RES  1K 1% EMPTY  pkg 0402LF  page 112 : A = P3V3_AUX ; B = FM_P2E_BUF2_EQA1
R9001  Q_RES  0 5% CHIP  pkg 0402LF  page 245 : A = GPU_PRSNT_N_ISO ; B = GPU_PRSNT_N_ISO_R1

(kicad_pcb
	(version 20260206)
	(generator "pcbnew")
	(generator_version "10.0")
	(general
		(thickness 1.6)
		(legacy_teardrops no)
	)
	(paper "A4")
	(title_block
		(title "04192023_DAF0TMB3IC0_F0TG_MB_C_brd_V02_OCP.brd")
		(comment 1 "Grand Teton / footprints 4755-4756 of 8354")
	)
	(layers
		(0 "F.Cu" signal "TOP")
		(4 "In1.Cu" signal "GND")
		(6 "In2.Cu" signal "IN1")
		(8 "In3.Cu" signal "GND1")
		(10 "In4.Cu" signal "IN2")
		(12 "In5.Cu" signal "GND2")
		(14 "In6.Cu" signal "IN3")
		(16 "In7.Cu" signal "GND3")
		(18 "In8.Cu" signal "VCC")
		(20 "In9.Cu" signal "VCC1")
		(22 "In10.Cu" signal "GND4")
		(24 "In11.Cu" signal "IN4")
		(26 "In12.Cu" signal "GND5")
		(28 "In13.Cu" signal "IN5")
		(30 "In14.Cu" signal "GND6")
		(32 "In15.Cu" signal "IN6")
		(34 "In16.Cu" signal "GND7")
		(2 "B.Cu" signal "BOTTOM")
		(9 "F.Adhes" user "F.Adhesive")
		(11 "B.Adhes" user "B.Adhesive")
		(13 "F.Paste" user "Package Geometry/Pastemask Top")
		(15 "B.Paste" user "Package Geometry/Pastemask Bottom")
		(5 "F.SilkS" user "Ref Des/Silkscreen Top")
		(7 "B.SilkS" user "Ref Des/Silkscreen Bottom")
		(1 "F.Mask" user "Board Geometry/Soldermask Top")
		(3 "B.Mask" user "Board Geometry/Soldermask Bottom")
		(17 "Dwgs.User" user "User.Drawings")
		(19 "Cmts.User" user "User.Comments")
		(21 "Eco1.User" user "User.Eco1")
		(23 "Eco2.User" user "User.Eco2")
		(25 "Edge.Cuts" user "Board Geometry/Outline")
		(27 "Margin" user)
		(31 "F.CrtYd" user "Package Geometry/Place Bound Top")
		(29 "B.CrtYd" user "Package Geometry/Place Bound Bottom")
		(35 "F.Fab" user "Ref Des/Assembly Top")
		(33 "B.Fab" user "Ref Des/Assembly Bottom")
	)
	(footprint ""
		(layer "F.Cu")
		(at 186.111642 -413.64408 90)
		(property "Reference" "R9001"
			(at 0 0 90)
			(layer "F.SilkS")
			(hide yes)
			(effects
				(font
					(size 1.27 1.27)
				)
			)
		)
		(property "Value" ""
			(at 0 0 90)
			(layer "F.Fab")
			(effects
				(font
					(size 1.27 1.27)
				)
			)
		)
		(duplicate_pad_numbers_are_jumpers no)
		(fp_line
			(start 0.7874 -0.4064)
			(end 0.7874 0.4064)
			(stroke
				(width 0.1524)
				(type default)
			)
			(layer "F.SilkS")
		)
		(fp_line
			(start -0.7874 -0.4064)
			(end 0.7874 -0.4064)
			(stroke
				(width 0.1524)
				(type default)
			)
			(layer "F.SilkS")
		)
		(fp_line
			(start 0.7874 0.4064)
			(end -0.7874 0.4064)
			(stroke
				(width 0.1524)
				(type default)
			)
			(layer "F.SilkS")
		)
		(fp_line
			(start -0.7874 0.4064)
			(end -0.7874 -0.4064)
			(stroke
				(width 0.1524)
				(type default)
			)
			(layer "F.SilkS")
		)
		(fp_line
			(start -0.12065 -0.305054)
			(end -0.12065 -0.2794)
			(stroke
				(width 0.1)
				(type default)
			)
			(layer "F.Fab")
		)
		(fp_line
			(start -0.67945 -0.305054)
			(end -0.12065 -0.305054)
			(stroke
				(width 0.1)
				(type default)
			)
			(layer "F.Fab")
		)
		(fp_line
			(start 0.67945 -0.3048)
			(end 0.67945 0.3048)
			(stroke
				(width 0.1)
				(type default)
			)
			(layer "F.Fab")
		)
		(fp_line
			(start 0.12065 -0.3048)
			(end 0.67945 -0.3048)
			(stroke
				(width 0.1)
				(type default)
			)
			(layer "F.Fab")
		)
		(fp_line
			(start 0.12065 -0.2794)
			(end 0.12065 -0.3048)
			(stroke
				(width 0.1)
				(type default)
			)
			(layer "F.Fab")
		)
		(fp_line
			(start -0.12065 -0.2794)
			(end 0.12065 -0.2794)
			(stroke
				(width 0.1)
				(type default)
			)
			(layer "F.Fab")
		)
		(fp_line
			(start 0.120396 0.2794)
			(end -0.12065 0.2794)
			(stroke
				(width 0.1)
				(type default)
			)
			(layer "F.Fab")
		)
		(fp_line
			(start -0.12065 0.2794)
			(end -0.12065 0.3048)
			(stroke
				(width 0.1)
				(type default)
			)
			(layer "F.Fab")
		)
		(fp_line
			(start 0.67945 0.3048)
			(end 0.120396 0.3048)
			(stroke
				(width 0.1)
				(type default)
			)
			(layer "F.Fab")
		)
		(fp_line
			(start 0.120396 0.3048)
			(end 0.120396 0.2794)
			(stroke
				(width 0.1)
				(type default)
			)
			(layer "F.Fab")
		)
		(fp_line
			(start -0.12065 0.3048)
			(end -0.67945 0.3048)
			(stroke
				(width 0.1)
				(type default)
			)
			(layer "F.Fab")
		)
		(fp_line
			(start -0.67945 0.3048)
			(end -0.67945 -0.305054)
			(stroke
				(width 0.1)
				(type default)
			)
			(layer "F.Fab")
		)
		(pad "1" smd circle
			(at -0.40005 0 90)
			(size 0 0)
			(layers "F.Cu" "F.Mask" "F.Paste")
			(net "GPU_PRSNT_N_ISO")
		)
		(pad "2" smd circle
			(at 0.40005 0 90)
			(size 0 0)
			(layers "F.Cu" "F.Mask" "F.Paste")
			(net "GPU_PRSNT_N_ISO_R1")
		)
	)
	(footprint ""
		(layer "F.Cu")
		(at 9.379458 -423.821098)
		(property "Reference" "R6171"
			(at 0 0 0)
			(layer "F.SilkS")
			(hide yes)
			(effects
				(font
					(size 1.27 1.27)
				)
			)
		)
		(property "Value" ""
			(at 0 0 0)
			(layer "F.Fab")
			(effects
				(font
					(size 1.27 1.27)
				)
			)
		)
		(duplicate_pad_numbers_are_jumpers no)
		(fp_line
			(start -0.7874 -0.4064)
			(end 0.7874 -0.4064)
			(stroke
				(width 0.1524)
				(type default)
			)
			(layer "F.SilkS")
		)
		(fp_line
			(start -0.7874 0.4064)
			(end -0.7874 -0.4064)
			(stroke
				(width 0.1524)
				(type default)
			)
			(layer "F.SilkS")
		)
		(fp_line
			(start 0.7874 -0.4064)
			(end 0.7874 0.4064)
			(stroke
				(width 0.1524)
				(type default)
			)
			(layer "F.SilkS")
		)
		(fp_line
			(start 0.7874 0.4064)
			(end -0.7874 0.4064)
			(stroke
				(width 0.1524)
				(type default)
			)
			(layer "F.SilkS")
		)
		(fp_line
			(start -0.67945 -0.305054)
			(end -0.12065 -0.305054)
			(stroke
				(width 0.1)
				(type default)
			)
			(layer "F.Fab")
		)
		(fp_line
			(start -0.67945 0.3048)
			(end -0.67945 -0.305054)
			(stroke
				(width 0.1)
				(type default)
			)
			(layer "F.Fab")
		)
		(fp_line
			(start -0.12065 -0.305054)
			(end -0.12065 -0.2794)
			(stroke
				(width 0.1)
				(type default)
			)
			(layer "F.Fab")
		)
		(fp_line
			(start -0.12065 -0.2794)
			(end 0.12065 -0.2794)
			(stroke
				(width 0.1)
				(type default)
			)
			(layer "F.Fab")
		)
		(fp_line
			(start -0.12065 0.2794)
			(end -0.12065 0.3048)
			(stroke
				(width 0.1)
				(type default)
			)
			(layer "F.Fab")
		)
		(fp_line
			(start -0.12065 0.3048)
			(end -0.67945 0.3048)
			(stroke
				(width 0.1)
				(type default)
			)
			(layer "F.Fab")
		)
		(fp_line
			(start 0.120396 0.2794)
			(end -0.12065 0.2794)
			(stroke
				(width 0.1)
				(type default)
			)
			(layer "F.Fab")
		)
		(fp_line
			(start 0.120396 0.3048)
			(end 0.120396 0.2794)
			(stroke
				(width 0.1)
				(type default)
			)
			(layer "F.Fab")
		)
		(fp_line
			(start 0.12065 -0.3048)
			(end 0.67945 -0.3048)
			(stroke
				(width 0.1)
				(type default)
			)
			(layer "F.Fab")
		)
		(fp_line
			(start 0.12065 -0.2794)
			(end 0.12065 -0.3048)
			(stroke
				(width 0.1)
				(type default)
			)
			(layer "F.Fab")
		)
		(fp_line
			(start 0.67945 -0.3048)
			(end 0.67945 0.3048)
			(stroke
				(width 0.1)
				(type default)
			)
			(layer "F.Fab")
		)
		(fp_line
			(start 0.67945 0.3048)
			(end 0.120396 0.3048)
			(stroke
				(width 0.1)
				(type default)
			)
			(layer "F.Fab")
		)
		(pad "1" smd circle
			(at -0.40005 0)
			(size 0 0)
			(layers "F.Cu" "F.Mask" "F.Paste")
			(net "P3V3_AUX")
		)
		(pad "2" smd circle
			(at 0.40005 0)
			(size 0 0)
			(layers "F.Cu" "F.Mask" "F.Paste")
			(net "FM_P2E_BUF2_EQA1")
		)
	)
)
